# BASEBOARD_FAB2 (Tioga Pass) — schematic netlist excerpt (pin names and nets, part order shuffled) for the footprints in the layout excerpt that follows; sources: Cadence DE-HDL packaged netlist, KiCad conversion of Wiwynn_Tioga_Pass_MB.brd

C2R8  CAP  0.22UF 16V 10% X7R  pkg 0402  page 106 : A = P3E_CPU0_PE3_OCP_TXP<6> ; B = P3E_OCP_CPU0_PE3_C_TXP<6>
C3P42  CAP_A  1.0UF 6.3V 10% X6S  pkg 0402V  page 96 : A = P3V3_STBY ; B = GND
SH5U1  SHUNT  EMPTY  pkg SH0201  page 221 : A = VR_PVTT_ABC_SNS ; B = PVTT_ABC

(kicad_pcb
	(version 20260206)
	(generator "pcbnew")
	(generator_version "10.0")
	(general
		(thickness 1.6)
		(legacy_teardrops no)
	)
	(paper "A4")
	(title_block
		(title "Wiwynn_Tioga_Pass_MB.brd")
		(comment 1 "Tioga Pass / footprints 3522-3524 of 4770")
	)
	(layers
		(0 "F.Cu" signal "TOP")
		(4 "In1.Cu" signal "L2GND")
		(6 "In2.Cu" signal "L3")
		(8 "In3.Cu" signal "L4GND")
		(10 "In4.Cu" signal "L5")
		(12 "In5.Cu" signal "L6GND")
		(14 "In6.Cu" signal "L7VCC")
		(16 "In7.Cu" signal "L8VCC")
		(18 "In8.Cu" signal "L9GND")
		(20 "In9.Cu" signal "L10")
		(22 "In10.Cu" signal "L11GND")
		(24 "In11.Cu" signal "L12")
		(26 "In12.Cu" signal "L13GND")
		(2 "B.Cu" signal "BOTTOM")
		(9 "F.Adhes" user "F.Adhesive")
		(11 "B.Adhes" user "B.Adhesive")
		(13 "F.Paste" user "Package Geometry/Pastemask Top")
		(15 "B.Paste" user "Package Geometry/Pastemask Bottom")
		(5 "F.SilkS" user "Ref Des/Silkscreen Top")
		(7 "B.SilkS" user "Ref Des/Silkscreen Bottom")
		(1 "F.Mask" user "Board Geometry/Soldermask Top")
		(3 "B.Mask" user "Board Geometry/Soldermask Bottom")
		(17 "Dwgs.User" user "User.Drawings")
		(19 "Cmts.User" user "User.Comments")
		(21 "Eco1.User" user "User.Eco1")
		(23 "Eco2.User" user "User.Eco2")
		(25 "Edge.Cuts" user "Board Geometry/Outline")
		(27 "Margin" user)
		(31 "F.CrtYd" user "Package Geometry/Place Bound Top")
		(29 "B.CrtYd" user "Package Geometry/Place Bound Bottom")
		(35 "F.Fab" user "Ref Des/Assembly Top")
		(33 "B.Fab" user "Ref Des/Assembly Bottom")
	)
	(footprint ""
		(layer "B.Cu")
		(at 443.633606 -52.342034)
		(property "Reference" "C2R8"
			(at 0 0 0)
			(layer "B.SilkS")
			(hide yes)
			(effects
				(font
					(size 1.27 1.27)
				)
				(justify mirror)
			)
		)
		(property "Value" ""
			(at 0 0 0)
			(layer "B.Fab")
			(effects
				(font
					(size 1.27 1.27)
				)
				(justify mirror)
			)
		)
		(duplicate_pad_numbers_are_jumpers no)
		(fp_poly
			(pts
				(xy -0.3048 -0.1016) (xy -0.3048 0.9906) (xy 0.3048 0.9906) (xy 0.3048 -0.1016)
			)
			(stroke
				(width 0)
				(type default)
			)
			(fill no)
			(layer "B.CrtYd")
		)
		(fp_line
			(start -0.3048 -0.1016)
			(end 0.3048 -0.1016)
			(stroke
				(width 0.1)
				(type default)
			)
			(layer "B.Fab")
		)
		(fp_line
			(start -0.3048 0.9906)
			(end -0.3048 -0.1016)
			(stroke
				(width 0.1)
				(type default)
			)
			(layer "B.Fab")
		)
		(fp_line
			(start 0.3048 -0.1016)
			(end 0.3048 0.9906)
			(stroke
				(width 0.1)
				(type default)
			)
			(layer "B.Fab")
		)
		(fp_line
			(start 0.3048 0.9906)
			(end -0.3048 0.9906)
			(stroke
				(width 0.1)
				(type default)
			)
			(layer "B.Fab")
		)
		(pad "1" smd rect
			(at 0 0 180)
			(size 0.508 0.508)
			(layers "B.Cu" "B.Mask" "B.Paste")
			(net "P3E_CPU0_PE3_OCP_TXP<6>")
		)
		(pad "2" smd rect
			(at 0 0.889 180)
			(size 0.508 0.508)
			(layers "B.Cu" "B.Mask" "B.Paste")
			(net "P3E_OCP_CPU0_PE3_C_TXP<6>")
		)
		(zone
			(layer "B.Cu")
			(hatch none 0.5)
			(connect_pads
				(clearance 0)
			)
			(min_thickness 0.25)
			(keepout
				(tracks allowed)
				(vias not_allowed)
				(pads allowed)
				(copperpour not_allowed)
				(footprints allowed)
			)
			(placement
				(enabled no)
				(sheetname "")
			)
			(fill
				(thermal_gap 0.5)
				(thermal_bridge_width 0.5)
				(island_removal_mode 0)
			)
			(polygon
				(pts
					(xy 443.887606 -52.088034) (xy 443.379606 -52.088034) (xy 443.379606 -51.707034) (xy 443.887606 -51.707034)
				)
			)
		)
		(zone
			(layer "B.Cu")
			(hatch none 0.5)
			(connect_pads
				(clearance 0)
			)
			(min_thickness 0.25)
			(keepout
				(tracks not_allowed)
				(vias allowed)
				(pads allowed)
				(copperpour not_allowed)
				(footprints allowed)
			)
			(placement
				(enabled no)
				(sheetname "")
			)
			(fill
				(thermal_gap 0.5)
				(thermal_bridge_width 0.5)
				(island_removal_mode 0)
			)
			(polygon
				(pts
					(xy 443.887606 -51.707034) (xy 443.379606 -51.707034) (xy 443.379606 -52.088034) (xy 443.887606 -52.088034)
				)
			)
		)
	)
	(footprint ""
		(layer "B.Cu")
		(at 260.863334 2.123694 -90)
		(property "Reference" "SH5U1"
			(at 0 0 90)
			(layer "B.SilkS")
			(hide yes)
			(effects
				(font
					(size 1.27 1.27)
				)
				(justify mirror)
			)
		)
		(property "Value" ""
			(at 0 0 90)
			(layer "B.Fab")
			(effects
				(font
					(size 1.27 1.27)
				)
				(justify mirror)
			)
		)
		(duplicate_pad_numbers_are_jumpers no)
		(fp_poly
			(pts
				(xy 0.1651 -0.0508) (xy 0.1651 0.5842) (xy -0.1651 0.5842) (xy -0.1651 -0.0508)
			)
			(stroke
				(width 0)
				(type default)
			)
			(fill no)
			(layer "B.CrtYd")
		)
		(fp_line
			(start -0.1651 0.5842)
			(end 0.1651 0.5842)
			(stroke
				(width 0.1)
				(type default)
			)
			(layer "B.Fab")
		)
		(fp_line
			(start 0.1651 0.5842)
			(end 0.1651 -0.0508)
			(stroke
				(width 0.1)
				(type default)
			)
			(layer "B.Fab")
		)
		(fp_line
			(start -0.1651 -0.0508)
			(end -0.1651 0.5842)
			(stroke
				(width 0.1)
				(type default)
			)
			(layer "B.Fab")
		)
		(fp_line
			(start 0.1651 -0.0508)
			(end -0.1651 -0.0508)
			(stroke
				(width 0.1)
				(type default)
			)
			(layer "B.Fab")
		)
		(pad "1" smd custom
			(at 0 0 270)
			(size 0.0762 0.0762)
			(layers "B.Cu" "B.Mask" "B.Paste")
			(net "VR_PVTT_ABC_SNS")
			(options
				(clearance outline)
				(anchor circle)
			)
			(primitives
				(gr_poly
					(pts
						(arc
							(start -0.1524 0.10795)
							(mid -0.098518 0.130268)
							(end -0.0762 0.18415)
						)
						(xy -0.0762 0.22225) (xy 0.0762 0.22225)
						(arc
							(start 0.0762 0.18415)
							(mid 0.098518 0.130268)
							(end 0.1524 0.10795)
						)
						(xy 0.1524 -0.22225) (xy -0.1524 -0.22225)
					)
					(width 0)
					(fill yes)
				)
			)
		)
		(pad "2" smd custom
			(at 0 0.5334 90)
			(size 0.0762 0.0762)
			(layers "B.Cu" "B.Mask" "B.Paste")
			(net "PVTT_ABC")
			(options
				(clearance outline)
				(anchor circle)
			)
			(primitives
				(gr_poly
					(pts
						(arc
							(start -0.1524 0.10795)
							(mid -0.098518 0.130268)
							(end -0.0762 0.18415)
						)
						(xy -0.0762 0.22225) (xy 0.0762 0.22225)
						(arc
							(start 0.0762 0.18415)
							(mid 0.098518 0.130268)
							(end 0.1524 0.10795)
						)
						(xy 0.1524 -0.22225) (xy -0.1524 -0.22225)
					)
					(width 0)
					(fill yes)
				)
			)
		)
	)
	(footprint ""
		(layer "B.Cu")
		(at 371.348 -64.008 -90)
		(property "Reference" "C3P42"
			(at 0 0 90)
			(layer "B.SilkS")
			(hide yes)
			(effects
				(font
					(size 1.27 1.27)
				)
				(justify mirror)
			)
		)
		(property "Value" ""
			(at 0 0 90)
			(layer "B.Fab")
			(effects
				(font
					(size 1.27 1.27)
				)
				(justify mirror)
			)
		)
		(duplicate_pad_numbers_are_jumpers no)
		(fp_poly
			(pts
				(xy -0.3048 -0.1016) (xy -0.3048 0.9906) (xy 0.3048 0.9906) (xy 0.3048 -0.1016)
			)
			(stroke
				(width 0)
				(type default)
			)
			(fill no)
			(layer "B.CrtYd")
		)
		(fp_line
			(start -0.3048 0.9906)
			(end -0.3048 -0.1016)
			(stroke
				(width 0.1)
				(type default)
			)
			(layer "B.Fab")
		)
		(fp_line
			(start 0.3048 0.9906)
			(end -0.3048 0.9906)
			(stroke
				(width 0.1)
				(type default)
			)
			(layer "B.Fab")
		)
		(fp_line
			(start -0.3048 -0.1016)
			(end 0.3048 -0.1016)
			(stroke
				(width 0.1)
				(type default)
			)
			(layer "B.Fab")
		)
		(fp_line
			(start 0.3048 -0.1016)
			(end 0.3048 0.9906)
			(stroke
				(width 0.1)
				(type default)
			)
			(layer "B.Fab")
		)
		(pad "1" smd rect
			(at 0 0 90)
			(size 0.508 0.508)
			(layers "B.Cu" "B.Mask" "B.Paste")
			(net "P3V3_STBY")
		)
		(pad "2" smd rect
			(at 0 0.889 90)
			(size 0.508 0.508)
			(layers "B.Cu" "B.Mask" "B.Paste")
			(net "GND")
		)
		(zone
			(layer "B.Cu")
			(hatch none 0.5)
			(connect_pads
				(clearance 0)
			)
			(min_thickness 0.25)
			(keepout
				(tracks not_allowed)
				(vias allowed)
				(pads allowed)
				(copperpour not_allowed)
				(footprints allowed)
			)
			(placement
				(enabled no)
				(sheetname "")
			)
			(fill
				(thermal_gap 0.5)
				(thermal_bridge_width 0.5)
				(island_removal_mode 0)
			)
			(polygon
				(pts
					(xy 370.713 -63.754) (xy 370.713 -64.262) (xy 371.094 -64.262) (xy 371.094 -63.754)
				)
			)
		)
		(zone
			(layer "B.Cu")
			(hatch none 0.5)
			(connect_pads
				(clearance 0)
			)
			(min_thickness 0.25)
			(keepout
				(tracks allowed)
				(vias not_allowed)
				(pads allowed)
				(copperpour not_allowed)
				(footprints allowed)
			)
			(placement
				(enabled no)
				(sheetname "")
			)
			(fill
				(thermal_gap 0.5)
				(thermal_bridge_width 0.5)
				(island_removal_mode 0)
			)
			(polygon
				(pts
					(xy 371.094 -63.754) (xy 371.094 -64.262) (xy 370.713 -64.262) (xy 370.713 -63.754)
				)
			)
		)
	)
)
